(kicad_pcb
	(version 20260206)
	(generator "pcbnew")
	(generator_version "10.0")
	(general
		(thickness 1.6)
		(legacy_teardrops no)
	)
	(paper "A4")
	(title_block
		(title "04192023_DAF0TMB3IC0_F0TG_MB_C_brd_V02_OCP.brd")
		(comment 1 "Grand Teton / footprints 568-573 of 8354")
	)
	(layers
		(0 "F.Cu" signal "TOP")
		(4 "In1.Cu" signal "GND")
		(6 "In2.Cu" signal "IN1")
		(8 "In3.Cu" signal "GND1")
		(10 "In4.Cu" signal "IN2")
		(12 "In5.Cu" signal "GND2")
		(14 "In6.Cu" signal "IN3")
		(16 "In7.Cu" signal "GND3")
		(18 "In8.Cu" signal "VCC")
		(20 "In9.Cu" signal "VCC1")
		(22 "In10.Cu" signal "GND4")
		(24 "In11.Cu" signal "IN4")
		(26 "In12.Cu" signal "GND5")
		(28 "In13.Cu" signal "IN5")
		(30 "In14.Cu" signal "GND6")
		(32 "In15.Cu" signal "IN6")
		(34 "In16.Cu" signal "GND7")
		(2 "B.Cu" signal "BOTTOM")
		(9 "F.Adhes" user "F.Adhesive")
		(11 "B.Adhes" user "B.Adhesive")
		(13 "F.Paste" user "Package Geometry/Pastemask Top")
		(15 "B.Paste" user "Package Geometry/Pastemask Bottom")
		(5 "F.SilkS" user "Ref Des/Silkscreen Top")
		(7 "B.SilkS" user "Ref Des/Silkscreen Bottom")
		(1 "F.Mask" user "Board Geometry/Soldermask Top")
		(3 "B.Mask" user "Board Geometry/Soldermask Bottom")
		(17 "Dwgs.User" user "User.Drawings")
		(19 "Cmts.User" user "User.Comments")
		(21 "Eco1.User" user "User.Eco1")
		(23 "Eco2.User" user "User.Eco2")
		(25 "Edge.Cuts" user "Board Geometry/Outline")
		(27 "Margin" user)
		(31 "F.CrtYd" user "Package Geometry/Place Bound Top")
		(29 "B.CrtYd" user "Package Geometry/Place Bound Bottom")
		(35 "F.Fab" user "Ref Des/Assembly Top")
		(33 "B.Fab" user "Ref Des/Assembly Bottom")
	)
	(footprint ""
		(layer "F.Cu")
		(at 69.324728 -170.662854 -90)
		(property "Reference" "PR524"
			(at 0 0 270)
			(layer "F.SilkS")
			(hide yes)
			(effects
				(font
					(size 1.27 1.27)
				)
			)
		)
		(property "Value" ""
			(at 0 0 270)
			(layer "F.Fab")
			(effects
				(font
					(size 1.27 1.27)
				)
			)
		)
		(duplicate_pad_numbers_are_jumpers no)
		(fp_line
			(start -0.7874 0.4064)
			(end -0.7874 -0.4064)
			(stroke
				(width 0.1524)
				(type default)
			)
			(layer "F.SilkS")
		)
		(fp_line
			(start 0.7874 0.4064)
			(end -0.7874 0.4064)
			(stroke
				(width 0.1524)
				(type default)
			)
			(layer "F.SilkS")
		)
		(fp_line
			(start -0.7874 -0.4064)
			(end 0.7874 -0.4064)
			(stroke
				(width 0.1524)
				(type default)
			)
			(layer "F.SilkS")
		)
		(fp_line
			(start 0.7874 -0.4064)
			(end 0.7874 0.4064)
			(stroke
				(width 0.1524)
				(type default)
			)
			(layer "F.SilkS")
		)
		(fp_line
			(start -0.67945 0.3048)
			(end -0.67945 -0.305054)
			(stroke
				(width 0.1)
				(type default)
			)
			(layer "F.Fab")
		)
		(fp_line
			(start -0.12065 0.3048)
			(end -0.67945 0.3048)
			(stroke
				(width 0.1)
				(type default)
			)
			(layer "F.Fab")
		)
		(fp_line
			(start 0.120396 0.3048)
			(end 0.120396 0.2794)
			(stroke
				(width 0.1)
				(type default)
			)
			(layer "F.Fab")
		)
		(fp_line
			(start 0.67945 0.3048)
			(end 0.120396 0.3048)
			(stroke
				(width 0.1)
				(type default)
			)
			(layer "F.Fab")
		)
		(fp_line
			(start -0.12065 0.2794)
			(end -0.12065 0.3048)
			(stroke
				(width 0.1)
				(type default)
			)
			(layer "F.Fab")
		)
		(fp_line
			(start 0.120396 0.2794)
			(end -0.12065 0.2794)
			(stroke
				(width 0.1)
				(type default)
			)
			(layer "F.Fab")
		)
		(fp_line
			(start -0.12065 -0.2794)
			(end 0.12065 -0.2794)
			(stroke
				(width 0.1)
				(type default)
			)
			(layer "F.Fab")
		)
		(fp_line
			(start 0.12065 -0.2794)
			(end 0.12065 -0.3048)
			(stroke
				(width 0.1)
				(type default)
			)
			(layer "F.Fab")
		)
		(fp_line
			(start 0.12065 -0.3048)
			(end 0.67945 -0.3048)
			(stroke
				(width 0.1)
				(type default)
			)
			(layer "F.Fab")
		)
		(fp_line
			(start 0.67945 -0.3048)
			(end 0.67945 0.3048)
			(stroke
				(width 0.1)
				(type default)
			)
			(layer "F.Fab")
		)
		(fp_line
			(start -0.67945 -0.305054)
			(end -0.12065 -0.305054)
			(stroke
				(width 0.1)
				(type default)
			)
			(layer "F.Fab")
		)
		(fp_line
			(start -0.12065 -0.305054)
			(end -0.12065 -0.2794)
			(stroke
				(width 0.1)
				(type default)
			)
			(layer "F.Fab")
		)
		(pad "1" smd circle
			(at -0.40005 0 270)
			(size 0 0)
			(layers "F.Cu" "F.Mask" "F.Paste")
			(net "SW_PVDDCR_CPU0_P1_SW6_RC")
		)
		(pad "2" smd circle
			(at 0.40005 0 270)
			(size 0 0)
			(layers "F.Cu" "F.Mask" "F.Paste")
			(net "GND")
		)
	)
	(footprint ""
		(layer "F.Cu")
		(at 174.78248 -385.578604 90)
		(property "Reference" "C368"
			(at 0 0 90)
			(layer "F.SilkS")
			(hide yes)
			(effects
				(font
					(size 1.27 1.27)
				)
			)
		)
		(property "Value" ""
			(at 0 0 90)
			(layer "F.Fab")
			(effects
				(font
					(size 1.27 1.27)
				)
			)
		)
		(duplicate_pad_numbers_are_jumpers no)
		(fp_line
			(start 0.7874 -0.4064)
			(end 0.7874 0.4064)
			(stroke
				(width 0.1524)
				(type default)
			)
			(layer "F.SilkS")
		)
		(fp_line
			(start -0.7874 -0.4064)
			(end 0.7874 -0.4064)
			(stroke
				(width 0.1524)
				(type default)
			)
			(layer "F.SilkS")
		)
		(fp_line
			(start 0.7874 0.4064)
			(end -0.7874 0.4064)
			(stroke
				(width 0.1524)
				(type default)
			)
			(layer "F.SilkS")
		)
		(fp_line
			(start -0.7874 0.4064)
			(end -0.7874 -0.4064)
			(stroke
				(width 0.1524)
				(type default)
			)
			(layer "F.SilkS")
		)
		(fp_line
			(start -0.12065 -0.305054)
			(end -0.12065 -0.2794)
			(stroke
				(width 0.1)
				(type default)
			)
			(layer "F.Fab")
		)
		(fp_line
			(start -0.67945 -0.305054)
			(end -0.12065 -0.305054)
			(stroke
				(width 0.1)
				(type default)
			)
			(layer "F.Fab")
		)
		(fp_line
			(start 0.67945 -0.3048)
			(end 0.67945 0.3048)
			(stroke
				(width 0.1)
				(type default)
			)
			(layer "F.Fab")
		)
		(fp_line
			(start 0.12065 -0.3048)
			(end 0.67945 -0.3048)
			(stroke
				(width 0.1)
				(type default)
			)
			(layer "F.Fab")
		)
		(fp_line
			(start 0.12065 -0.2794)
			(end 0.12065 -0.3048)
			(stroke
				(width 0.1)
				(type default)
			)
			(layer "F.Fab")
		)
		(fp_line
			(start -0.12065 -0.2794)
			(end 0.12065 -0.2794)
			(stroke
				(width 0.1)
				(type default)
			)
			(layer "F.Fab")
		)
		(fp_line
			(start 0.120396 0.2794)
			(end -0.12065 0.2794)
			(stroke
				(width 0.1)
				(type default)
			)
			(layer "F.Fab")
		)
		(fp_line
			(start -0.12065 0.2794)
			(end -0.12065 0.3048)
			(stroke
				(width 0.1)
				(type default)
			)
			(layer "F.Fab")
		)
		(fp_line
			(start 0.67945 0.3048)
			(end 0.120396 0.3048)
			(stroke
				(width 0.1)
				(type default)
			)
			(layer "F.Fab")
		)
		(fp_line
			(start 0.120396 0.3048)
			(end 0.120396 0.2794)
			(stroke
				(width 0.1)
				(type default)
			)
			(layer "F.Fab")
		)
		(fp_line
			(start -0.12065 0.3048)
			(end -0.67945 0.3048)
			(stroke
				(width 0.1)
				(type default)
			)
			(layer "F.Fab")
		)
		(fp_line
			(start -0.67945 0.3048)
			(end -0.67945 -0.305054)
			(stroke
				(width 0.1)
				(type default)
			)
			(layer "F.Fab")
		)
		(pad "1" smd circle
			(at -0.40005 0 90)
			(size 0 0)
			(layers "F.Cu" "F.Mask" "F.Paste")
			(net "P1V8_CPU1_RT_1D")
		)
		(pad "2" smd circle
			(at 0.40005 0 90)
			(size 0 0)
			(layers "F.Cu" "F.Mask" "F.Paste")
			(net "GND")
		)
	)
	(footprint ""
		(layer "F.Cu")
		(at 196.977 -100.294948 90)
		(property "Reference" "R3477"
			(at 0 0 90)
			(layer "F.SilkS")
			(hide yes)
			(effects
				(font
					(size 1.27 1.27)
				)
			)
		)
		(property "Value" ""
			(at 0 0 90)
			(layer "F.Fab")
			(effects
				(font
					(size 1.27 1.27)
				)
			)
		)
		(duplicate_pad_numbers_are_jumpers no)
		(fp_line
			(start 0.7874 -0.4064)
			(end 0.7874 0.4064)
			(stroke
				(width 0.1524)
				(type default)
			)
			(layer "F.SilkS")
		)
		(fp_line
			(start -0.7874 -0.4064)
			(end 0.7874 -0.4064)
			(stroke
				(width 0.1524)
				(type default)
			)
			(layer "F.SilkS")
		)
		(fp_line
			(start 0.7874 0.4064)
			(end -0.7874 0.4064)
			(stroke
				(width 0.1524)
				(type default)
			)
			(layer "F.SilkS")
		)
		(fp_line
			(start -0.7874 0.4064)
			(end -0.7874 -0.4064)
			(stroke
				(width 0.1524)
				(type default)
			)
			(layer "F.SilkS")
		)
		(fp_line
			(start -0.12065 -0.305054)
			(end -0.12065 -0.2794)
			(stroke
				(width 0.1)
				(type default)
			)
			(layer "F.Fab")
		)
		(fp_line
			(start -0.67945 -0.305054)
			(end -0.12065 -0.305054)
			(stroke
				(width 0.1)
				(type default)
			)
			(layer "F.Fab")
		)
		(fp_line
			(start 0.67945 -0.3048)
			(end 0.67945 0.3048)
			(stroke
				(width 0.1)
				(type default)
			)
			(layer "F.Fab")
		)
		(fp_line
			(start 0.12065 -0.3048)
			(end 0.67945 -0.3048)
			(stroke
				(width 0.1)
				(type default)
			)
			(layer "F.Fab")
		)
		(fp_line
			(start 0.12065 -0.2794)
			(end 0.12065 -0.3048)
			(stroke
				(width 0.1)
				(type default)
			)
			(layer "F.Fab")
		)
		(fp_line
			(start -0.12065 -0.2794)
			(end 0.12065 -0.2794)
			(stroke
				(width 0.1)
				(type default)
			)
			(layer "F.Fab")
		)
		(fp_line
			(start 0.120396 0.2794)
			(end -0.12065 0.2794)
			(stroke
				(width 0.1)
				(type default)
			)
			(layer "F.Fab")
		)
		(fp_line
			(start -0.12065 0.2794)
			(end -0.12065 0.3048)
			(stroke
				(width 0.1)
				(type default)
			)
			(layer "F.Fab")
		)
		(fp_line
			(start 0.67945 0.3048)
			(end 0.120396 0.3048)
			(stroke
				(width 0.1)
				(type default)
			)
			(layer "F.Fab")
		)
		(fp_line
			(start 0.120396 0.3048)
			(end 0.120396 0.2794)
			(stroke
				(width 0.1)
				(type default)
			)
			(layer "F.Fab")
		)
		(fp_line
			(start -0.12065 0.3048)
			(end -0.67945 0.3048)
			(stroke
				(width 0.1)
				(type default)
			)
			(layer "F.Fab")
		)
		(fp_line
			(start -0.67945 0.3048)
			(end -0.67945 -0.305054)
			(stroke
				(width 0.1)
				(type default)
			)
			(layer "F.Fab")
		)
		(pad "1" smd circle
			(at -0.40005 0 90)
			(size 0 0)
			(layers "F.Cu" "F.Mask" "F.Paste")
			(net "GPU_NVS_PWR_BRAKE_N")
		)
		(pad "2" smd circle
			(at 0.40005 0 90)
			(size 0 0)
			(layers "F.Cu" "F.Mask" "F.Paste")
			(net "GPU_NVS_PWR_BRAKE_R_N")
		)
	)
	(footprint ""
		(layer "F.Cu")
		(at 172.593 -132.715 90)
		(property "Reference" "C6122"
			(at 0 0 90)
			(layer "F.SilkS")
			(hide yes)
			(effects
				(font
					(size 1.27 1.27)
				)
			)
		)
		(property "Value" ""
			(at 0 0 90)
			(layer "F.Fab")
			(effects
				(font
					(size 1.27 1.27)
				)
			)
		)
		(duplicate_pad_numbers_are_jumpers no)
		(fp_line
			(start 0.7874 -0.4064)
			(end 0.7874 0.4064)
			(stroke
				(width 0.1524)
				(type default)
			)
			(layer "F.SilkS")
		)
		(fp_line
			(start -0.7874 -0.4064)
			(end 0.7874 -0.4064)
			(stroke
				(width 0.1524)
				(type default)
			)
			(layer "F.SilkS")
		)
		(fp_line
			(start 0.7874 0.4064)
			(end -0.7874 0.4064)
			(stroke
				(width 0.1524)
				(type default)
			)
			(layer "F.SilkS")
		)
		(fp_line
			(start -0.7874 0.4064)
			(end -0.7874 -0.4064)
			(stroke
				(width 0.1524)
				(type default)
			)
			(layer "F.SilkS")
		)
		(fp_line
			(start -0.12065 -0.305054)
			(end -0.12065 -0.2794)
			(stroke
				(width 0.1)
				(type default)
			)
			(layer "F.Fab")
		)
		(fp_line
			(start -0.67945 -0.305054)
			(end -0.12065 -0.305054)
			(stroke
				(width 0.1)
				(type default)
			)
			(layer "F.Fab")
		)
		(fp_line
			(start 0.67945 -0.3048)
			(end 0.67945 0.3048)
			(stroke
				(width 0.1)
				(type default)
			)
			(layer "F.Fab")
		)
		(fp_line
			(start 0.12065 -0.3048)
			(end 0.67945 -0.3048)
			(stroke
				(width 0.1)
				(type default)
			)
			(layer "F.Fab")
		)
		(fp_line
			(start 0.12065 -0.2794)
			(end 0.12065 -0.3048)
			(stroke
				(width 0.1)
				(type default)
			)
			(layer "F.Fab")
		)
		(fp_line
			(start -0.12065 -0.2794)
			(end 0.12065 -0.2794)
			(stroke
				(width 0.1)
				(type default)
			)
			(layer "F.Fab")
		)
		(fp_line
			(start 0.120396 0.2794)
			(end -0.12065 0.2794)
			(stroke
				(width 0.1)
				(type default)
			)
			(layer "F.Fab")
		)
		(fp_line
			(start -0.12065 0.2794)
			(end -0.12065 0.3048)
			(stroke
				(width 0.1)
				(type default)
			)
			(layer "F.Fab")
		)
		(fp_line
			(start 0.67945 0.3048)
			(end 0.120396 0.3048)
			(stroke
				(width 0.1)
				(type default)
			)
			(layer "F.Fab")
		)
		(fp_line
			(start 0.120396 0.3048)
			(end 0.120396 0.2794)
			(stroke
				(width 0.1)
				(type default)
			)
			(layer "F.Fab")
		)
		(fp_line
			(start -0.12065 0.3048)
			(end -0.67945 0.3048)
			(stroke
				(width 0.1)
				(type default)
			)
			(layer "F.Fab")
		)
		(fp_line
			(start -0.67945 0.3048)
			(end -0.67945 -0.305054)
			(stroke
				(width 0.1)
				(type default)
			)
			(layer "F.Fab")
		)
		(pad "1" smd circle
			(at -0.40005 0 90)
			(size 0 0)
			(layers "F.Cu" "F.Mask" "F.Paste")
			(net "P5V")
		)
		(pad "2" smd circle
			(at 0.40005 0 90)
			(size 0 0)
			(layers "F.Cu" "F.Mask" "F.Paste")
			(net "GND")
		)
	)
	(footprint ""
		(layer "F.Cu")
		(at 386.211826 -64.3255 180)
		(property "Reference" "R1632"
			(at 0 0 180)
			(layer "F.SilkS")
			(hide yes)
			(effects
				(font
					(size 1.27 1.27)
				)
			)
		)
		(property "Value" ""
			(at 0 0 180)
			(layer "F.Fab")
			(effects
				(font
					(size 1.27 1.27)
				)
			)
		)
		(duplicate_pad_numbers_are_jumpers no)
		(fp_line
			(start 0.7874 0.4064)
			(end -0.7874 0.4064)
			(stroke
				(width 0.1524)
				(type default)
			)
			(layer "F.SilkS")
		)
		(fp_line
			(start 0.7874 -0.4064)
			(end 0.7874 0.4064)
			(stroke
				(width 0.1524)
				(type default)
			)
			(layer "F.SilkS")
		)
		(fp_line
			(start -0.7874 0.4064)
			(end -0.7874 -0.4064)
			(stroke
				(width 0.1524)
				(type default)
			)
			(layer "F.SilkS")
		)
		(fp_line
			(start -0.7874 -0.4064)
			(end 0.7874 -0.4064)
			(stroke
				(width 0.1524)
				(type default)
			)
			(layer "F.SilkS")
		)
		(fp_line
			(start 0.67945 0.3048)
			(end 0.120396 0.3048)
			(stroke
				(width 0.1)
				(type default)
			)
			(layer "F.Fab")
		)
		(fp_line
			(start 0.67945 -0.3048)
			(end 0.67945 0.3048)
			(stroke
				(width 0.1)
				(type default)
			)
			(layer "F.Fab")
		)
		(fp_line
			(start 0.12065 -0.2794)
			(end 0.12065 -0.3048)
			(stroke
				(width 0.1)
				(type default)
			)
			(layer "F.Fab")
		)
		(fp_line
			(start 0.12065 -0.3048)
			(end 0.67945 -0.3048)
			(stroke
				(width 0.1)
				(type default)
			)
			(layer "F.Fab")
		)
		(fp_line
			(start 0.120396 0.3048)
			(end 0.120396 0.2794)
			(stroke
				(width 0.1)
				(type default)
			)
			(layer "F.Fab")
		)
		(fp_line
			(start 0.120396 0.2794)
			(end -0.12065 0.2794)
			(stroke
				(width 0.1)
				(type default)
			)
			(layer "F.Fab")
		)
		(fp_line
			(start -0.12065 0.3048)
			(end -0.67945 0.3048)
			(stroke
				(width 0.1)
				(type default)
			)
			(layer "F.Fab")
		)
		(fp_line
			(start -0.12065 0.2794)
			(end -0.12065 0.3048)
			(stroke
				(width 0.1)
				(type default)
			)
			(layer "F.Fab")
		)
		(fp_line
			(start -0.12065 -0.2794)
			(end 0.12065 -0.2794)
			(stroke
				(width 0.1)
				(type default)
			)
			(layer "F.Fab")
		)
		(fp_line
			(start -0.12065 -0.305054)
			(end -0.12065 -0.2794)
			(stroke
				(width 0.1)
				(type default)
			)
			(layer "F.Fab")
		)
		(fp_line
			(start -0.67945 0.3048)
			(end -0.67945 -0.305054)
			(stroke
				(width 0.1)
				(type default)
			)
			(layer "F.Fab")
		)
		(fp_line
			(start -0.67945 -0.305054)
			(end -0.12065 -0.305054)
			(stroke
				(width 0.1)
				(type default)
			)
			(layer "F.Fab")
		)
		(pad "1" smd circle
			(at -0.40005 0 180)
			(size 0 0)
			(layers "F.Cu" "F.Mask" "F.Paste")
			(net "HDT_CPU0_HDT_CONN_TESTEN")
		)
		(pad "2" smd circle
			(at 0.40005 0 180)
			(size 0 0)
			(layers "F.Cu" "F.Mask" "F.Paste")
			(net "CPU0_HDT_CONN_TESTEN")
		)
	)
	(footprint ""
		(layer "F.Cu")
		(at 453.892666 -390.076944 -90)
		(property "Reference" "PL6506"
			(at 1.075944 -5.747004 90)
			(unlocked yes)
			(layer "F.SilkS")
			(effects
				(font
					(size 0.7874 0.5842)
					(thickness 0.1524)
				)
				(justify left)
			)
		)
		(property "Value" ""
			(at 0 0 270)
			(layer "F.Fab")
			(effects
				(font
					(size 1.27 1.27)
				)
			)
		)
		(duplicate_pad_numbers_are_jumpers no)
		(fp_line
			(start -3.24993 3.24993)
			(end -3.24993 2.2352)
			(stroke
				(width 0.1524)
				(type default)
			)
			(layer "F.SilkS")
		)
		(fp_line
			(start 3.24993 3.24993)
			(end -3.24993 3.24993)
			(stroke
				(width 0.1524)
				(type default)
			)
			(layer "F.SilkS")
		)
		(fp_line
			(start 3.24993 2.2352)
			(end 3.24993 3.24993)
			(stroke
				(width 0.1524)
				(type default)
			)
			(layer "F.SilkS")
		)
		(fp_line
			(start -3.24993 -2.2352)
			(end -3.24993 -3.24993)
			(stroke
				(width 0.1524)
				(type default)
			)
			(layer "F.SilkS")
		)
		(fp_line
			(start -3.24993 -3.24993)
			(end 3.24993 -3.24993)
			(stroke
				(width 0.1524)
				(type default)
			)
			(layer "F.SilkS")
		)
		(fp_line
			(start 3.24993 -3.24993)
			(end 3.24993 -2.2352)
			(stroke
				(width 0.1524)
				(type default)
			)
			(layer "F.SilkS")
		)
		(fp_line
			(start -3.24993 3.24993)
			(end -3.24993 -3.24993)
			(stroke
				(width 0.1)
				(type default)
			)
			(layer "F.Fab")
		)
		(fp_line
			(start 3.24993 3.24993)
			(end -3.24993 3.24993)
			(stroke
				(width 0.1)
				(type default)
			)
			(layer "F.Fab")
		)
		(fp_line
			(start -3.24993 -3.24993)
			(end 3.24993 -3.24993)
			(stroke
				(width 0.1)
				(type default)
			)
			(layer "F.Fab")
		)
		(fp_line
			(start 3.24993 -3.24993)
			(end 3.24993 3.24993)
			(stroke
				(width 0.1)
				(type default)
			)
			(layer "F.Fab")
		)
		(pad "1" smd rect
			(at -2.29997 0 270)
			(size 2.0066 4.2164)
			(layers "F.Cu" "F.Mask" "F.Paste")
			(net "SW_P0V9_RETIMER_CPU0_SW2")
		)
		(pad "2" smd rect
			(at 2.29997 0 270)
			(size 2.0066 4.2164)
			(layers "F.Cu" "F.Mask" "F.Paste")
			(net "P0V9_CPU0_RT_2D")
		)
	)
)
